# SCM (Grand Teton) — schematic netlist excerpt (pin names and nets, part order shuffled) for the footprints in the layout excerpt that follows; sources: Cadence DE-HDL packaged netlist, KiCad conversion of 12092022_DA0F0TMDCD0_F0T_Management_Board_D_brd_V3_OCP.brd

C268  Q_CAP  0.1UF 25V 10% X7R  pkg 0402  page 30 : A = P3V3_AUX ; B = GND
R692  Q_RES  2.2K 5% CHIP  pkg 0402LF  page 27 : A = P3V3_AUX ; B = SMB_BMC_MM15_SDA

(kicad_pcb
	(version 20260206)
	(generator "pcbnew")
	(generator_version "10.0")
	(general
		(thickness 1.6)
		(legacy_teardrops no)
	)
	(paper "A4")
	(title_block
		(title "12092022_DA0F0TMDCD0_F0T_Management_Board_D_brd_V3_OCP.brd")
		(comment 1 "Grand Teton / footprints 276-277 of 1440")
	)
	(layers
		(0 "F.Cu" signal "TOP")
		(4 "In1.Cu" signal "GND")
		(6 "In2.Cu" signal "IN1")
		(8 "In3.Cu" signal "GND1")
		(10 "In4.Cu" signal "IN2")
		(12 "In5.Cu" signal "VCC")
		(14 "In6.Cu" signal "VCC1")
		(16 "In7.Cu" signal "IN3")
		(18 "In8.Cu" signal "GND2")
		(20 "In9.Cu" signal "IN4")
		(22 "In10.Cu" signal "GND3")
		(2 "B.Cu" signal "BOTTOM")
		(9 "F.Adhes" user "F.Adhesive")
		(11 "B.Adhes" user "B.Adhesive")
		(13 "F.Paste" user "Package Geometry/Pastemask Top")
		(15 "B.Paste" user "Package Geometry/Pastemask Bottom")
		(5 "F.SilkS" user "Ref Des/Silkscreen Top")
		(7 "B.SilkS" user "Ref Des/Silkscreen Bottom")
		(1 "F.Mask" user "Board Geometry/Soldermask Top")
		(3 "B.Mask" user "Board Geometry/Soldermask Bottom")
		(17 "Dwgs.User" user "User.Drawings")
		(19 "Cmts.User" user "User.Comments")
		(21 "Eco1.User" user "User.Eco1")
		(23 "Eco2.User" user "User.Eco2")
		(25 "Edge.Cuts" user "Board Geometry/Outline")
		(27 "Margin" user)
		(31 "F.CrtYd" user "Package Geometry/Place Bound Top")
		(29 "B.CrtYd" user "Package Geometry/Place Bound Bottom")
		(35 "F.Fab" user "Ref Des/Assembly Top")
		(33 "B.Fab" user "Ref Des/Assembly Bottom")
	)
	(footprint ""
		(layer "F.Cu")
		(at 29.1592 -65.8622 90)
		(property "Reference" "C268"
			(at 0 0 90)
			(layer "F.SilkS")
			(hide yes)
			(effects
				(font
					(size 1.27 1.27)
				)
			)
		)
		(property "Value" ""
			(at 0 0 90)
			(layer "F.Fab")
			(effects
				(font
					(size 1.27 1.27)
				)
			)
		)
		(duplicate_pad_numbers_are_jumpers no)
		(fp_line
			(start 0.7874 -0.4064)
			(end 0.7874 0.4064)
			(stroke
				(width 0.1524)
				(type default)
			)
			(layer "F.SilkS")
		)
		(fp_line
			(start -0.7874 -0.4064)
			(end 0.7874 -0.4064)
			(stroke
				(width 0.1524)
				(type default)
			)
			(layer "F.SilkS")
		)
		(fp_line
			(start 0.7874 0.4064)
			(end -0.7874 0.4064)
			(stroke
				(width 0.1524)
				(type default)
			)
			(layer "F.SilkS")
		)
		(fp_line
			(start -0.7874 0.4064)
			(end -0.7874 -0.4064)
			(stroke
				(width 0.1524)
				(type default)
			)
			(layer "F.SilkS")
		)
		(fp_line
			(start -0.12065 -0.305054)
			(end -0.12065 -0.2794)
			(stroke
				(width 0.1)
				(type default)
			)
			(layer "F.Fab")
		)
		(fp_line
			(start -0.67945 -0.305054)
			(end -0.12065 -0.305054)
			(stroke
				(width 0.1)
				(type default)
			)
			(layer "F.Fab")
		)
		(fp_line
			(start 0.67945 -0.3048)
			(end 0.67945 0.3048)
			(stroke
				(width 0.1)
				(type default)
			)
			(layer "F.Fab")
		)
		(fp_line
			(start 0.12065 -0.3048)
			(end 0.67945 -0.3048)
			(stroke
				(width 0.1)
				(type default)
			)
			(layer "F.Fab")
		)
		(fp_line
			(start 0.12065 -0.2794)
			(end 0.12065 -0.3048)
			(stroke
				(width 0.1)
				(type default)
			)
			(layer "F.Fab")
		)
		(fp_line
			(start -0.12065 -0.2794)
			(end 0.12065 -0.2794)
			(stroke
				(width 0.1)
				(type default)
			)
			(layer "F.Fab")
		)
		(fp_line
			(start 0.120396 0.2794)
			(end -0.12065 0.2794)
			(stroke
				(width 0.1)
				(type default)
			)
			(layer "F.Fab")
		)
		(fp_line
			(start -0.12065 0.2794)
			(end -0.12065 0.3048)
			(stroke
				(width 0.1)
				(type default)
			)
			(layer "F.Fab")
		)
		(fp_line
			(start 0.67945 0.3048)
			(end 0.120396 0.3048)
			(stroke
				(width 0.1)
				(type default)
			)
			(layer "F.Fab")
		)
		(fp_line
			(start 0.120396 0.3048)
			(end 0.120396 0.2794)
			(stroke
				(width 0.1)
				(type default)
			)
			(layer "F.Fab")
		)
		(fp_line
			(start -0.12065 0.3048)
			(end -0.67945 0.3048)
			(stroke
				(width 0.1)
				(type default)
			)
			(layer "F.Fab")
		)
		(fp_line
			(start -0.67945 0.3048)
			(end -0.67945 -0.305054)
			(stroke
				(width 0.1)
				(type default)
			)
			(layer "F.Fab")
		)
		(pad "1" smd circle
			(at -0.40005 0 90)
			(size 0 0)
			(layers "F.Cu" "F.Mask" "F.Paste")
			(net "P3V3_AUX")
		)
		(pad "2" smd circle
			(at 0.40005 0 90)
			(size 0 0)
			(layers "F.Cu" "F.Mask" "F.Paste")
			(net "GND")
		)
	)
	(footprint ""
		(layer "F.Cu")
		(at 51.816 -30.861 90)
		(property "Reference" "R692"
			(at 0 0 90)
			(layer "F.SilkS")
			(hide yes)
			(effects
				(font
					(size 1.27 1.27)
				)
			)
		)
		(property "Value" ""
			(at 0 0 90)
			(layer "F.Fab")
			(effects
				(font
					(size 1.27 1.27)
				)
			)
		)
		(duplicate_pad_numbers_are_jumpers no)
		(fp_line
			(start 0.7874 -0.4064)
			(end 0.7874 0.4064)
			(stroke
				(width 0.1524)
				(type default)
			)
			(layer "F.SilkS")
		)
		(fp_line
			(start -0.7874 -0.4064)
			(end 0.7874 -0.4064)
			(stroke
				(width 0.1524)
				(type default)
			)
			(layer "F.SilkS")
		)
		(fp_line
			(start 0.7874 0.4064)
			(end -0.7874 0.4064)
			(stroke
				(width 0.1524)
				(type default)
			)
			(layer "F.SilkS")
		)
		(fp_line
			(start -0.7874 0.4064)
			(end -0.7874 -0.4064)
			(stroke
				(width 0.1524)
				(type default)
			)
			(layer "F.SilkS")
		)
		(fp_line
			(start -0.12065 -0.305054)
			(end -0.12065 -0.2794)
			(stroke
				(width 0.1)
				(type default)
			)
			(layer "F.Fab")
		)
		(fp_line
			(start -0.67945 -0.305054)
			(end -0.12065 -0.305054)
			(stroke
				(width 0.1)
				(type default)
			)
			(layer "F.Fab")
		)
		(fp_line
			(start 0.67945 -0.3048)
			(end 0.67945 0.3048)
			(stroke
				(width 0.1)
				(type default)
			)
			(layer "F.Fab")
		)
		(fp_line
			(start 0.12065 -0.3048)
			(end 0.67945 -0.3048)
			(stroke
				(width 0.1)
				(type default)
			)
			(layer "F.Fab")
		)
		(fp_line
			(start 0.12065 -0.2794)
			(end 0.12065 -0.3048)
			(stroke
				(width 0.1)
				(type default)
			)
			(layer "F.Fab")
		)
		(fp_line
			(start -0.12065 -0.2794)
			(end 0.12065 -0.2794)
			(stroke
				(width 0.1)
				(type default)
			)
			(layer "F.Fab")
		)
		(fp_line
			(start 0.120396 0.2794)
			(end -0.12065 0.2794)
			(stroke
				(width 0.1)
				(type default)
			)
			(layer "F.Fab")
		)
		(fp_line
			(start -0.12065 0.2794)
			(end -0.12065 0.3048)
			(stroke
				(width 0.1)
				(type default)
			)
			(layer "F.Fab")
		)
		(fp_line
			(start 0.67945 0.3048)
			(end 0.120396 0.3048)
			(stroke
				(width 0.1)
				(type default)
			)
			(layer "F.Fab")
		)
		(fp_line
			(start 0.120396 0.3048)
			(end 0.120396 0.2794)
			(stroke
				(width 0.1)
				(type default)
			)
			(layer "F.Fab")
		)
		(fp_line
			(start -0.12065 0.3048)
			(end -0.67945 0.3048)
			(stroke
				(width 0.1)
				(type default)
			)
			(layer "F.Fab")
		)
		(fp_line
			(start -0.67945 0.3048)
			(end -0.67945 -0.305054)
			(stroke
				(width 0.1)
				(type default)
			)
			(layer "F.Fab")
		)
		(pad "1" smd circle
			(at -0.40005 0 90)
			(size 0 0)
			(layers "F.Cu" "F.Mask" "F.Paste")
			(net "P3V3_AUX")
		)
		(pad "2" smd circle
			(at 0.40005 0 90)
			(size 0 0)
			(layers "F.Cu" "F.Mask" "F.Paste")
			(net "SMB_BMC_MM15_SDA")
		)
	)
)
